FILE_TYPE = MULTI_PHYS_TABLE;

PART 'RS53317LR'

{========================================================================================}
:VALUE       | PART_TYPE | MATERIAL | PART_NUMBER    = STANDARD | LIFECYCLE          | PART_NUMBER   | JEDEC_TYPE        | DESCRIPTION             | MANUFTR | MANUF_PN    | RD_CMPLS_LVL | CMPLS_LVL | FROM_PJ    | CLASS | DIP_SMD | DATA                | EE_CHECK_LIST | FP_ECN          | PSL | CREATOR | STATUS | MSD | ESD_CDM | ESD_HBM | ESD_MM | PIN_LENGTH_SHORT_PIN | PIN_LENGTH_LONG_PIN | CREATEDAY  ;
{========================================================================================}
 'RS53317LR' | 'SMLF'    | 'IC'     | 'AL053317005'(!) = ''       | ''               | 'AL053317005' |'QFN14_0-5_3X2XB'| 'IC(14P)RS53317LR(QFN)' | 'RDS'   | 'RS53317LR' | 'EP(V1)'     | 'EP(V1)'  | 'MF6-NINA' | 'IC'  | ''      | 'RDS_RS53317LR.pdf' | ''            | 'RS53317LR.msg' | ''  | ''      | ''     | ''  | ''      | ''      | ''     | '0 MILS'             | '0 MILS'            | '20220525'
 'RS53317LR' | 'SMLF'    | 'EMPTY'  | 'AL053317005'(!) = ''       | ''               | 'AL053317005' |'QFN14_0-5_3X2XB'| 'IC(14P)RS53317LR(QFN)' | 'RDS'   | 'RS53317LR' | 'EP(V1)'     | 'EP(V1)'  | 'MF6-NINA' | 'IC'  | ''      | 'RDS_RS53317LR.pdf' | ''            | 'RS53317LR.msg' | ''  | ''      | ''     | ''  | ''      | ''      | ''     | '0 MILS'             | '0 MILS'            | '20220525'

END_PART

END.

